FILE_TYPE = CONNECTIVITY;
{Allegro Design Entry HDL 17.2-2016 S081 (4005846) 1/11/2022}
"PAGE_NUMBER" = 240;
0"NC";
1"P3V3_AUX\g";
2"P3V3_AUX\g";
3"P12V_S3_AUX_CPU0_NVDIMM\g";
4"P12V_AUX\g";
5"P12V_S3_AUX_CPU1_NVDIMM\g";
6"P12V_AUX\g";
7"GND\g";
8"GND\g";
9"GND\g";
10"GND\g";
11"GND\g";
12"GND\g";
13"NC_HSC_TYPE_VINM";
14"HSC_TYPE_ADC";
15"NC_HSC_TYPE_VINP";
16"SMB_HSC_TYPE_ADC_SDA";
17"HSC_TYPE_ADC_A1";
18"TP_HSC_TYPE_ADC_ALERT";
19"NC_HSC_TYPE_NC5";
20"NC_HSC_TYPE_NC4";
21"NC_HSC_TYPE_NC3";
22"NC_HSC_TYPE_NC2";
23"NC_HSC_TYPE_NC1";
24"NC_HSC_TYPE_NC0";
25"SMB_HSC_TYPE_ADC_SCL";
26"HSC_TYPE_ADC_A0";
27"SMB_LM75_0_3V3AUX_SDA";
28"SMB_LM75_0_3V3AUX_SCL";
29"PVCCD_HV_CPU0_NVDIMM_ISENSE"CDS_PHYS_NET_NAME"PVCCD_HV_CPU0_NVDIMM_ISENSE";
30"P12V_AUX_CPU1_DIMM_ISEN_P"CDS_PHYS_NET_NAME"P12V_AUX_CPU1_DIMM_ISEN_P";
31"P12V_AUX_CPU1_DIMM_ISEN_N"CDS_PHYS_NET_NAME"P12V_AUX_CPU1_DIMM_ISEN_N";
32"P12V_AUX_CPU0_DIMM_ISEN_N"CDS_PHYS_NET_NAME"P12V_AUX_CPU0_DIMM_ISEN_N";
33"P12V_AUX_CPU0_DIMM_ISEN_P"CDS_PHYS_NET_NAME"P12V_AUX_CPU0_DIMM_ISEN_P";
34"P12V_AUX_CPU0_DIMM_ISEN_P"CDS_PHYS_NET_NAME"P12V_AUX_CPU0_DIMM_ISEN_P";
35"PVCCD_HV_CPU1_NVDIMM_ISENSE"CDS_PHYS_NET_NAME"PVCCD_HV_CPU1_NVDIMM_ISENSE";
36"P12V_AUX_CPU0_DIMM_ISEN_N"CDS_PHYS_NET_NAME"P12V_AUX_CPU0_DIMM_ISEN_N";
37"P12V_AUX_CPU1_DIMM_ISEN_N"CDS_PHYS_NET_NAME"P12V_AUX_CPU1_DIMM_ISEN_N";
38"P12V_AUX_CPU1_DIMM_ISEN_P"CDS_PHYS_NET_NAME"P12V_AUX_CPU1_DIMM_ISEN_P";
%"Q_RES_4P_12"
"1","(-2400,-2525)","1","pure_quanta","I11";
;
PART_NUMBER"SP_CS+001DFR10"
WATTAGE"3W"
TOLERANCE"1%"
VALUE"0.001"
PART_TYPE"SMLF"
MATERIAL"CHIP"
LOCATION"R1838"
CDS_LIB"pure_quanta"
CDS_LMAN_SYM_OUTLINE"-50,75,50,-75"
NEEDS_NO_SIZE"TRUE"
$SEC"1"
CDS_SEC"1";
"4"
$PN"4"36;
"3"
$PN"3"33;
"2"
$PN"2"3;
"1"
$PN"1"4;
%"UNIVERSAL_POWER"
"1","(-1550,-2175)","0","logical_power","I13";
;
HDL_POWER"P12V_S3_AUX_CPU0_NVDIMM"
CDS_LIB"logical_power";
"A"3;
%"UNIVERSAL_GND"
"1","(-1275,-525)","0","logical_power","I14";
;
HDL_POWER"GND"
CDS_LIB"logical_power";
"A"11;
%"Q_CAP"
"1","(-1275,-225)","0","pure_quanta","I15";
;
PART_NUMBER"CH4104K1B00"
MATERIAL"EMPTY"
TOLERANCE"10%"
VOLTAGE"25V"
VALUE"0.1UF"
ROOM"HSC1_BOM2"
PACK_TYPE"0402"
$LOCATION"C2363"
CDS_LIB"pure_quanta"
CDS_LOCATION"C2363"
$SEC"1"
CDS_SEC"1";
"B"
$PN"2"11;
"A"
$PN"1"14;
%"Q_RES"
"2","(-1325,550)","0","pure_quanta","I16";
;
PART_NUMBER"CS00002JB13"
TOLERANCE"5%"
ROOM"HSC1_BOM2"
WATTAGE"1/16W"
PACK_TYPE"0402LF"
MATERIAL"EMPTY"
VALUE"0"
$LOCATION"R4691"
CDS_LIB"pure_quanta"
CDS_LOCATION"R4691"
$SEC"1"
CDS_SEC"1";
"A"
$PN"1"26;
"B"
$PN"2"16;
%"UNIVERSAL_GND"
"1","(-2700,600)","0","logical_power","I17";
;
CDS_LIB"logical_power"
HDL_POWER"GND";
"A"10;
%"Q_RES"
"1","(-2125,725)","0","pure_quanta","I18";
;
PART_NUMBER"CS24702FB06"
MATERIAL"EMPTY"
TOLERANCE"1%"
WATTAGE"1/16W"
VALUE"4.7K"
PACK_TYPE"0402LF"
$LOCATION"R4688"
CDS_LIB"pure_quanta"
CDS_LOCATION"R4688"
$SEC"1"
CDS_SEC"1";
"B"
$PN"2"26;
"A"
$PN"1"10;
%"Q_RES"
"1","(-2125,800)","0","pure_quanta","I19";
;
PART_NUMBER"CS24702FB06"
ROOM"HSC1_BOM2"
PACK_TYPE"0402LF"
MATERIAL"EMPTY"
WATTAGE"1/16W"
TOLERANCE"1%"
VALUE"4.7K"
$LOCATION"R4687"
CDS_LIB"pure_quanta"
CDS_LOCATION"R4687"
$SEC"1"
CDS_SEC"1";
"B"
$PN"2"17;
"A"
$PN"1"10;
%"UNIVERSAL_POWER"
"1","(-3275,-3625)","0","logical_power","I2";
;
HDL_POWER"P12V_AUX"
CDS_LIB"logical_power";
"A"6;
%"INA183A1IDBVR"
"1","(1850,-3975)","0","pure_quanta","I22";
;
PART_NUMBER"AL000183000"
MATERIAL"EMPTY"
VALUE"INA183A1IDBVR"
PART_TYPE"SMLF"
LOCATION"U103"
SEC_TYPE""
CDS_LIB"pure_quanta"
CDS_LMAN_SYM_OUTLINE"-175,125,175,-125"
NEEDS_NO_SIZE"TRUE"
SEC"1";
"IN+"
$PN"5"30;
"IN-"
$PN"4"31;
"OUT"
$PN"3"35;
"GND1"
$PN"2"9;
"GND0"
$PN"1"9;
%"UNIVERSAL_GND"
"1","(2375,-4200)","0","logical_power","I23";
;
CDS_LIB"logical_power"
HDL_POWER"GND";
"A"9;
%"UNIVERSAL_GND"
"1","(525,-400)","0","logical_power","I28";
;
HDL_POWER"GND"
CDS_LIB"logical_power";
"A"12;
%"INA183A1IDBVR"
"1","(1850,-2550)","0","pure_quanta","I29";
;
PART_NUMBER"AL000183000"
MATERIAL"EMPTY"
PART_TYPE"SMLF"
VALUE"INA183A1IDBVR"
LOCATION"U102"
SEC_TYPE""
CDS_LIB"pure_quanta"
NEEDS_NO_SIZE"TRUE"
CDS_LMAN_SYM_OUTLINE"-175,125,175,-125"
SEC"1";
"IN+"
$PN"5"34;
"IN-"
$PN"4"32;
"OUT"
$PN"3"29;
"GND1"
$PN"2"8;
"GND0"
$PN"1"8;
%"Q_RES_4P_12"
"1","(-2375,-3975)","1","pure_quanta","I3";
;
PART_NUMBER"SP_CS+001DFR10"
PART_TYPE"SMLF"
VALUE"0.001"
WATTAGE"3W"
TOLERANCE"1%"
MATERIAL"CHIP"
LOCATION"R1837"
CDS_LIB"pure_quanta"
CDS_LMAN_SYM_OUTLINE"-50,75,50,-75"
NEEDS_NO_SIZE"TRUE"
$SEC"1"
CDS_SEC"1";
"4"
$PN"4"37;
"3"
$PN"3"38;
"2"
$PN"2"5;
"1"
$PN"1"6;
%"UNIVERSAL_GND"
"1","(2375,-2775)","0","logical_power","I30";
;
CDS_LIB"logical_power"
HDL_POWER"GND";
"A"8;
%"UNIVERSAL_GND"
"1","(-700,525)","0","logical_power","I32";
;
CDS_LIB"logical_power"
HDL_POWER"GND";
"A"7;
%"Q_CAP"
"1","(-700,800)","0","pure_quanta","I33";
;
PART_NUMBER"CH4104K1B00"
PACK_TYPE"0402"
ROOM"HSC1_BOM2"
TOLERANCE"10%"
MATERIAL"EMPTY"
VALUE"0.1UF"
VOLTAGE"25V"
$LOCATION"C2364"
CDS_LIB"pure_quanta"
CDS_LOCATION"C2364"
$SEC"1"
CDS_SEC"1";
"B"
$PN"2"7;
"A"
$PN"1"2;
%"UNIVERSAL_POWER"
"1","(-450,1200)","0","logical_power","I34";
;
HDL_POWER"P3V3_AUX"
CDS_LIB"logical_power";
"A"2;
%"Q_RES"
"2","(1350,900)","0","pure_quanta","I35";
;
PART_NUMBER"CS24702FB06"
ROOM"HSC1_BOM2"
TOLERANCE"1%"
PACK_TYPE"0402LF"
WATTAGE"1/16W"
VALUE"4.7K"
MATERIAL"EMPTY"
$LOCATION"R4692"
CDS_LIB"pure_quanta"
CDS_LOCATION"R4692"
$SEC"1"
CDS_SEC"1";
"A"
$PN"1"1;
"B"
$PN"2"18;
%"UNIVERSAL_POWER"
"1","(1350,1100)","0","logical_power","I36";
;
HDL_POWER"P3V3_AUX"
CDS_LIB"logical_power";
"A"1;
%"Q_RES"
"1","(-1775,200)","0","pure_quanta","I37";
;
PART_NUMBER"CS03322FB03"
TOLERANCE"1%"
VALUE"33.2"
MATERIAL"EMPTY"
ROOM"HSC1_BOM2"
$LOCATION"R4690"
CDS_LIB"pure_quanta"
PACK_TYPE"0402LF"
WATTAGE"1/16W"
CDS_LOCATION"R4690"
$SEC"1"
CDS_SEC"1";
"B"
$PN"2"16;
"A"
$PN"1"27;
%"Q_RES"
"1","(-1775,250)","0","pure_quanta","I38";
;
PART_NUMBER"CS03322FB03"
MATERIAL"EMPTY"
PACK_TYPE"0402LF"
WATTAGE"1/16W"
ROOM"HSC1_BOM2"
TOLERANCE"1%"
VALUE"33.2"
$LOCATION"R4689"
CDS_LIB"pure_quanta"
CDS_LOCATION"R4689"
$SEC"1"
CDS_SEC"1";
"B"
$PN"2"25;
"A"
$PN"1"28;
%"INA230AIRGTR"
"1","(50,250)","0","pure_quanta","I39";
;
PART_NUMBER"AL000230001"
PART_TYPE"SMLF"
MATERIAL"EMPTY"
VALUE"INA230AIRGTR"
ROOM"HSC1_BOM2"
LOCATION"U331"
CDS_LIB"pure_quanta"
CDS_LMAN_SYM_OUTLINE"-250,300,250,-300"
NEEDS_NO_SIZE"TRUE"
$SEC"1"
CDS_SEC"1";
"TH"
$PN"TH"12;
"GND"
$PN"10"12;
"NC5"
$PN"16"19;
"NC4"
$PN"15"20;
"NC3"
$PN"14"21;
"NC2"
$PN"8"22;
"NC1"
$PN"7"23;
"NC0"
$PN"6"24;
"ALERT"
$PN"3"18;
"IN-"
$PN"12"13;
"IN+"
$PN"13"15;
"BUS"
$PN"11"14;
"SDA"
$PN"4"16;
"SCL"
$PN"5"25;
"A0"
$PN"2"26;
"A1"
$PN"1"17;
"VS"
$PN"9"2;
%"UNIVERSAL_POWER"
"1","(-1525,-3625)","0","logical_power","I4";
;
HDL_POWER"P12V_S3_AUX_CPU1_NVDIMM"
CDS_LIB"logical_power";
"A"5;
%"UNIVERSAL_POWER"
"1","(-3300,-2175)","0","logical_power","I7";
;
HDL_POWER"P12V_AUX"
CDS_LIB"logical_power";
"A"4;
END.
